(kicad_pcb
	(version 20260206)
	(generator "pcbnew")
	(generator_version "10.0")
	(general
		(thickness 1.6)
		(legacy_teardrops no)
	)
	(paper "A4")
	(title_block
		(title "04192023_DAF0TMB3IC0_F0TG_MB_C_brd_V02_OCP.brd")
		(comment 1 "Grand Teton / footprints 5921-5929 of 8354")
	)
	(layers
		(0 "F.Cu" signal "TOP")
		(4 "In1.Cu" signal "GND")
		(6 "In2.Cu" signal "IN1")
		(8 "In3.Cu" signal "GND1")
		(10 "In4.Cu" signal "IN2")
		(12 "In5.Cu" signal "GND2")
		(14 "In6.Cu" signal "IN3")
		(16 "In7.Cu" signal "GND3")
		(18 "In8.Cu" signal "VCC")
		(20 "In9.Cu" signal "VCC1")
		(22 "In10.Cu" signal "GND4")
		(24 "In11.Cu" signal "IN4")
		(26 "In12.Cu" signal "GND5")
		(28 "In13.Cu" signal "IN5")
		(30 "In14.Cu" signal "GND6")
		(32 "In15.Cu" signal "IN6")
		(34 "In16.Cu" signal "GND7")
		(2 "B.Cu" signal "BOTTOM")
		(9 "F.Adhes" user "F.Adhesive")
		(11 "B.Adhes" user "B.Adhesive")
		(13 "F.Paste" user "Package Geometry/Pastemask Top")
		(15 "B.Paste" user "Package Geometry/Pastemask Bottom")
		(5 "F.SilkS" user "Ref Des/Silkscreen Top")
		(7 "B.SilkS" user "Ref Des/Silkscreen Bottom")
		(1 "F.Mask" user "Board Geometry/Soldermask Top")
		(3 "B.Mask" user "Board Geometry/Soldermask Bottom")
		(17 "Dwgs.User" user "User.Drawings")
		(19 "Cmts.User" user "User.Comments")
		(21 "Eco1.User" user "User.Eco1")
		(23 "Eco2.User" user "User.Eco2")
		(25 "Edge.Cuts" user "Board Geometry/Outline")
		(27 "Margin" user)
		(31 "F.CrtYd" user "Package Geometry/Place Bound Top")
		(29 "B.CrtYd" user "Package Geometry/Place Bound Bottom")
		(35 "F.Fab" user "Ref Des/Assembly Top")
		(33 "B.Fab" user "Ref Des/Assembly Bottom")
	)
	(footprint ""
		(layer "B.Cu")
		(at 20.480782 -412.850584 180)
		(property "Reference" "PR6802"
			(at 0 0 0)
			(layer "B.SilkS")
			(hide yes)
			(effects
				(font
					(size 1.27 1.27)
				)
				(justify mirror)
			)
		)
		(property "Value" ""
			(at 0 0 0)
			(layer "B.Fab")
			(effects
				(font
					(size 1.27 1.27)
				)
				(justify mirror)
			)
		)
		(duplicate_pad_numbers_are_jumpers no)
		(fp_line
			(start 0.7874 0.4064)
			(end 0.7874 -0.4064)
			(stroke
				(width 0.1524)
				(type default)
			)
			(layer "B.SilkS")
		)
		(fp_line
			(start 0.7874 -0.4064)
			(end -0.7874 -0.4064)
			(stroke
				(width 0.1524)
				(type default)
			)
			(layer "B.SilkS")
		)
		(fp_line
			(start -0.7874 0.4064)
			(end 0.7874 0.4064)
			(stroke
				(width 0.1524)
				(type default)
			)
			(layer "B.SilkS")
		)
		(fp_line
			(start -0.7874 -0.4064)
			(end -0.7874 0.4064)
			(stroke
				(width 0.1524)
				(type default)
			)
			(layer "B.SilkS")
		)
		(fp_line
			(start 0.67945 0.3048)
			(end 0.67945 -0.305054)
			(stroke
				(width 0.1)
				(type default)
			)
			(layer "B.Fab")
		)
		(fp_line
			(start 0.67945 -0.305054)
			(end 0.12065 -0.305054)
			(stroke
				(width 0.1)
				(type default)
			)
			(layer "B.Fab")
		)
		(fp_line
			(start 0.12065 0.3048)
			(end 0.67945 0.3048)
			(stroke
				(width 0.1)
				(type default)
			)
			(layer "B.Fab")
		)
		(fp_line
			(start 0.12065 0.2794)
			(end 0.12065 0.3048)
			(stroke
				(width 0.1)
				(type default)
			)
			(layer "B.Fab")
		)
		(fp_line
			(start 0.12065 -0.2794)
			(end -0.12065 -0.2794)
			(stroke
				(width 0.1)
				(type default)
			)
			(layer "B.Fab")
		)
		(fp_line
			(start 0.12065 -0.305054)
			(end 0.12065 -0.2794)
			(stroke
				(width 0.1)
				(type default)
			)
			(layer "B.Fab")
		)
		(fp_line
			(start -0.120396 0.3048)
			(end -0.120396 0.2794)
			(stroke
				(width 0.1)
				(type default)
			)
			(layer "B.Fab")
		)
		(fp_line
			(start -0.120396 0.2794)
			(end 0.12065 0.2794)
			(stroke
				(width 0.1)
				(type default)
			)
			(layer "B.Fab")
		)
		(fp_line
			(start -0.12065 -0.2794)
			(end -0.12065 -0.3048)
			(stroke
				(width 0.1)
				(type default)
			)
			(layer "B.Fab")
		)
		(fp_line
			(start -0.12065 -0.3048)
			(end -0.67945 -0.3048)
			(stroke
				(width 0.1)
				(type default)
			)
			(layer "B.Fab")
		)
		(fp_line
			(start -0.67945 0.3048)
			(end -0.120396 0.3048)
			(stroke
				(width 0.1)
				(type default)
			)
			(layer "B.Fab")
		)
		(fp_line
			(start -0.67945 -0.3048)
			(end -0.67945 0.3048)
			(stroke
				(width 0.1)
				(type default)
			)
			(layer "B.Fab")
		)
		(pad "1" smd circle
			(at 0.40005 0)
			(size 0 0)
			(layers "B.Cu" "B.Mask" "B.Paste")
			(net "TP_P0V9_RETIMER_CPU1_SVID_ALERT_N")
		)
		(pad "2" smd circle
			(at -0.40005 0)
			(size 0 0)
			(layers "B.Cu" "B.Mask" "B.Paste")
			(net "GND")
		)
	)
	(footprint ""
		(layer "B.Cu")
		(at 304.436018 -409.560014 90)
		(property "Reference" "PJ09_P0_N"
			(at 0 0 90)
			(layer "B.SilkS")
			(hide yes)
			(effects
				(font
					(size 1.27 1.27)
				)
				(justify mirror)
			)
		)
		(property "Value" ""
			(at 0 0 90)
			(layer "B.Fab")
			(effects
				(font
					(size 1.27 1.27)
				)
				(justify mirror)
			)
		)
		(duplicate_pad_numbers_are_jumpers no)
		(zone
			(layer "In11.Cu")
			(hatch none 0.5)
			(connect_pads
				(clearance 0)
			)
			(min_thickness 0.25)
			(keepout
				(tracks allowed)
				(vias not_allowed)
				(pads allowed)
				(copperpour not_allowed)
				(footprints allowed)
			)
			(placement
				(enabled no)
				(sheetname "")
			)
			(fill
				(thermal_gap 0.5)
				(thermal_bridge_width 0.5)
				(island_removal_mode 0)
			)
			(polygon
				(pts
					(xy 304.626518 -409.775914) (xy 304.626518 -409.344114) (xy 304.245518 -409.344114) (xy 304.245518 -409.775914)
				)
			)
		)
	)
	(footprint ""
		(layer "B.Cu")
		(at 77.94625 -387.05028)
		(property "Reference" "C301"
			(at 0 0 0)
			(layer "B.SilkS")
			(hide yes)
			(effects
				(font
					(size 1.27 1.27)
				)
				(justify mirror)
			)
		)
		(property "Value" ""
			(at 0 0 0)
			(layer "B.Fab")
			(effects
				(font
					(size 1.27 1.27)
				)
				(justify mirror)
			)
		)
		(duplicate_pad_numbers_are_jumpers no)
		(fp_line
			(start -0.299974 -0.150114)
			(end -0.299974 0.150114)
			(stroke
				(width 0.1)
				(type default)
			)
			(layer "B.Fab")
		)
		(fp_line
			(start -0.299974 0.150114)
			(end 0.299974 0.150114)
			(stroke
				(width 0.1)
				(type default)
			)
			(layer "B.Fab")
		)
		(fp_line
			(start 0.299974 -0.150114)
			(end -0.299974 -0.150114)
			(stroke
				(width 0.1)
				(type default)
			)
			(layer "B.Fab")
		)
		(fp_line
			(start 0.299974 0.150114)
			(end 0.299974 -0.150114)
			(stroke
				(width 0.1)
				(type default)
			)
			(layer "B.Fab")
		)
		(pad "1" smd rect
			(at 0.2667 0 180)
			(size 0.3048 0.381)
			(layers "B.Cu" "B.Mask" "B.Paste")
			(net "P0V9_CPU1_RT1_2A")
		)
		(pad "2" smd rect
			(at -0.2667 0 180)
			(size 0.3048 0.381)
			(layers "B.Cu" "B.Mask" "B.Paste")
			(net "GND")
		)
	)
	(footprint ""
		(layer "B.Cu")
		(at 128.18618 -37.09543 -90)
		(property "Reference" "C6062"
			(at 0 0 90)
			(layer "B.SilkS")
			(hide yes)
			(effects
				(font
					(size 1.27 1.27)
				)
				(justify mirror)
			)
		)
		(property "Value" ""
			(at 0 0 90)
			(layer "B.Fab")
			(effects
				(font
					(size 1.27 1.27)
				)
				(justify mirror)
			)
		)
		(duplicate_pad_numbers_are_jumpers no)
		(fp_line
			(start -0.7874 0.4064)
			(end 0.7874 0.4064)
			(stroke
				(width 0.1524)
				(type default)
			)
			(layer "B.SilkS")
		)
		(fp_line
			(start 0.7874 0.4064)
			(end 0.7874 -0.4064)
			(stroke
				(width 0.1524)
				(type default)
			)
			(layer "B.SilkS")
		)
		(fp_line
			(start -0.7874 -0.4064)
			(end -0.7874 0.4064)
			(stroke
				(width 0.1524)
				(type default)
			)
			(layer "B.SilkS")
		)
		(fp_line
			(start 0.7874 -0.4064)
			(end -0.7874 -0.4064)
			(stroke
				(width 0.1524)
				(type default)
			)
			(layer "B.SilkS")
		)
		(fp_line
			(start -0.67945 0.3048)
			(end -0.120396 0.3048)
			(stroke
				(width 0.1)
				(type default)
			)
			(layer "B.Fab")
		)
		(fp_line
			(start -0.120396 0.3048)
			(end -0.120396 0.2794)
			(stroke
				(width 0.1)
				(type default)
			)
			(layer "B.Fab")
		)
		(fp_line
			(start 0.12065 0.3048)
			(end 0.67945 0.3048)
			(stroke
				(width 0.1)
				(type default)
			)
			(layer "B.Fab")
		)
		(fp_line
			(start 0.67945 0.3048)
			(end 0.67945 -0.305054)
			(stroke
				(width 0.1)
				(type default)
			)
			(layer "B.Fab")
		)
		(fp_line
			(start -0.120396 0.2794)
			(end 0.12065 0.2794)
			(stroke
				(width 0.1)
				(type default)
			)
			(layer "B.Fab")
		)
		(fp_line
			(start 0.12065 0.2794)
			(end 0.12065 0.3048)
			(stroke
				(width 0.1)
				(type default)
			)
			(layer "B.Fab")
		)
		(fp_line
			(start -0.12065 -0.2794)
			(end -0.12065 -0.3048)
			(stroke
				(width 0.1)
				(type default)
			)
			(layer "B.Fab")
		)
		(fp_line
			(start 0.12065 -0.2794)
			(end -0.12065 -0.2794)
			(stroke
				(width 0.1)
				(type default)
			)
			(layer "B.Fab")
		)
		(fp_line
			(start -0.67945 -0.3048)
			(end -0.67945 0.3048)
			(stroke
				(width 0.1)
				(type default)
			)
			(layer "B.Fab")
		)
		(fp_line
			(start -0.12065 -0.3048)
			(end -0.67945 -0.3048)
			(stroke
				(width 0.1)
				(type default)
			)
			(layer "B.Fab")
		)
		(fp_line
			(start 0.12065 -0.305054)
			(end 0.12065 -0.2794)
			(stroke
				(width 0.1)
				(type default)
			)
			(layer "B.Fab")
		)
		(fp_line
			(start 0.67945 -0.305054)
			(end 0.12065 -0.305054)
			(stroke
				(width 0.1)
				(type default)
			)
			(layer "B.Fab")
		)
		(pad "1" smd circle
			(at 0.40005 0 90)
			(size 0 0)
			(layers "B.Cu" "B.Mask" "B.Paste")
			(net "P1V2_AUX")
		)
		(pad "2" smd circle
			(at -0.40005 0 90)
			(size 0 0)
			(layers "B.Cu" "B.Mask" "B.Paste")
			(net "GND")
		)
	)
	(footprint ""
		(layer "B.Cu")
		(at 28.50388 -402.540724 -90)
		(property "Reference" "PC6818"
			(at 0 0 90)
			(layer "B.SilkS")
			(hide yes)
			(effects
				(font
					(size 1.27 1.27)
				)
				(justify mirror)
			)
		)
		(property "Value" ""
			(at 0 0 90)
			(layer "B.Fab")
			(effects
				(font
					(size 1.27 1.27)
				)
				(justify mirror)
			)
		)
		(duplicate_pad_numbers_are_jumpers no)
		(fp_line
			(start -1.524 0.762)
			(end 1.524 0.762)
			(stroke
				(width 0.1524)
				(type default)
			)
			(layer "B.SilkS")
		)
		(fp_line
			(start 1.524 0.762)
			(end 1.524 -0.762)
			(stroke
				(width 0.1524)
				(type default)
			)
			(layer "B.SilkS")
		)
		(fp_line
			(start -1.524 -0.762)
			(end -1.524 0.762)
			(stroke
				(width 0.1524)
				(type default)
			)
			(layer "B.SilkS")
		)
		(fp_line
			(start 1.524 -0.762)
			(end -1.524 -0.762)
			(stroke
				(width 0.1524)
				(type default)
			)
			(layer "B.SilkS")
		)
		(fp_line
			(start -1.1049 0.724916)
			(end -1.1049 -0.724916)
			(stroke
				(width 0.1)
				(type default)
			)
			(layer "B.Fab")
		)
		(fp_line
			(start 1.1049 0.724916)
			(end -1.1049 0.724916)
			(stroke
				(width 0.1)
				(type default)
			)
			(layer "B.Fab")
		)
		(fp_line
			(start -1.1049 -0.724916)
			(end 1.1049 -0.724916)
			(stroke
				(width 0.1)
				(type default)
			)
			(layer "B.Fab")
		)
		(fp_line
			(start 1.1049 -0.724916)
			(end 1.1049 0.724916)
			(stroke
				(width 0.1)
				(type default)
			)
			(layer "B.Fab")
		)
		(pad "1" smd rect
			(at 0.889 0 270)
			(size 1.016 1.27)
			(layers "B.Cu" "B.Mask" "B.Paste")
			(net "SW_P12V_AUX_P0V9_RETIMER_CPU1_FLT")
		)
		(pad "2" smd rect
			(at -0.889 0 270)
			(size 1.016 1.27)
			(layers "B.Cu" "B.Mask" "B.Paste")
			(net "GND")
		)
	)
	(footprint ""
		(layer "B.Cu")
		(at 10.066782 -407.262584)
		(property "Reference" "PR6813"
			(at 0 0 0)
			(layer "B.SilkS")
			(hide yes)
			(effects
				(font
					(size 1.27 1.27)
				)
				(justify mirror)
			)
		)
		(property "Value" ""
			(at 0 0 0)
			(layer "B.Fab")
			(effects
				(font
					(size 1.27 1.27)
				)
				(justify mirror)
			)
		)
		(duplicate_pad_numbers_are_jumpers no)
		(fp_line
			(start -0.7874 -0.4064)
			(end -0.7874 0.4064)
			(stroke
				(width 0.1524)
				(type default)
			)
			(layer "B.SilkS")
		)
		(fp_line
			(start -0.7874 0.4064)
			(end 0.7874 0.4064)
			(stroke
				(width 0.1524)
				(type default)
			)
			(layer "B.SilkS")
		)
		(fp_line
			(start 0.7874 -0.4064)
			(end -0.7874 -0.4064)
			(stroke
				(width 0.1524)
				(type default)
			)
			(layer "B.SilkS")
		)
		(fp_line
			(start 0.7874 0.4064)
			(end 0.7874 -0.4064)
			(stroke
				(width 0.1524)
				(type default)
			)
			(layer "B.SilkS")
		)
		(fp_line
			(start -0.67945 -0.3048)
			(end -0.67945 0.3048)
			(stroke
				(width 0.1)
				(type default)
			)
			(layer "B.Fab")
		)
		(fp_line
			(start -0.67945 0.3048)
			(end -0.120396 0.3048)
			(stroke
				(width 0.1)
				(type default)
			)
			(layer "B.Fab")
		)
		(fp_line
			(start -0.12065 -0.3048)
			(end -0.67945 -0.3048)
			(stroke
				(width 0.1)
				(type default)
			)
			(layer "B.Fab")
		)
		(fp_line
			(start -0.12065 -0.2794)
			(end -0.12065 -0.3048)
			(stroke
				(width 0.1)
				(type default)
			)
			(layer "B.Fab")
		)
		(fp_line
			(start -0.120396 0.2794)
			(end 0.12065 0.2794)
			(stroke
				(width 0.1)
				(type default)
			)
			(layer "B.Fab")
		)
		(fp_line
			(start -0.120396 0.3048)
			(end -0.120396 0.2794)
			(stroke
				(width 0.1)
				(type default)
			)
			(layer "B.Fab")
		)
		(fp_line
			(start 0.12065 -0.305054)
			(end 0.12065 -0.2794)
			(stroke
				(width 0.1)
				(type default)
			)
			(layer "B.Fab")
		)
		(fp_line
			(start 0.12065 -0.2794)
			(end -0.12065 -0.2794)
			(stroke
				(width 0.1)
				(type default)
			)
			(layer "B.Fab")
		)
		(fp_line
			(start 0.12065 0.2794)
			(end 0.12065 0.3048)
			(stroke
				(width 0.1)
				(type default)
			)
			(layer "B.Fab")
		)
		(fp_line
			(start 0.12065 0.3048)
			(end 0.67945 0.3048)
			(stroke
				(width 0.1)
				(type default)
			)
			(layer "B.Fab")
		)
		(fp_line
			(start 0.67945 -0.305054)
			(end 0.12065 -0.305054)
			(stroke
				(width 0.1)
				(type default)
			)
			(layer "B.Fab")
		)
		(fp_line
			(start 0.67945 0.3048)
			(end 0.67945 -0.305054)
			(stroke
				(width 0.1)
				(type default)
			)
			(layer "B.Fab")
		)
		(pad "1" smd circle
			(at 0.40005 0 180)
			(size 0 0)
			(layers "B.Cu" "B.Mask" "B.Paste")
			(net "P0V9_RETIMER_CPU1_VINSEN")
		)
		(pad "2" smd circle
			(at -0.40005 0 180)
			(size 0 0)
			(layers "B.Cu" "B.Mask" "B.Paste")
			(net "GND")
		)
	)
	(footprint ""
		(layer "B.Cu")
		(at 350.306132 -395.148562 90)
		(property "Reference" "C618"
			(at 0 0 90)
			(layer "B.SilkS")
			(hide yes)
			(effects
				(font
					(size 1.27 1.27)
				)
				(justify mirror)
			)
		)
		(property "Value" ""
			(at 0 0 90)
			(layer "B.Fab")
			(effects
				(font
					(size 1.27 1.27)
				)
				(justify mirror)
			)
		)
		(duplicate_pad_numbers_are_jumpers no)
		(fp_line
			(start 0.299974 -0.150114)
			(end -0.299974 -0.150114)
			(stroke
				(width 0.1)
				(type default)
			)
			(layer "B.Fab")
		)
		(fp_line
			(start -0.299974 -0.150114)
			(end -0.299974 0.150114)
			(stroke
				(width 0.1)
				(type default)
			)
			(layer "B.Fab")
		)
		(fp_line
			(start 0.299974 0.150114)
			(end 0.299974 -0.150114)
			(stroke
				(width 0.1)
				(type default)
			)
			(layer "B.Fab")
		)
		(fp_line
			(start -0.299974 0.150114)
			(end 0.299974 0.150114)
			(stroke
				(width 0.1)
				(type default)
			)
			(layer "B.Fab")
		)
		(pad "1" smd rect
			(at 0.2667 0 270)
			(size 0.3048 0.381)
			(layers "B.Cu" "B.Mask" "B.Paste")
			(net "P0V9_CPU0_RT1_2A")
		)
		(pad "2" smd rect
			(at -0.2667 0 270)
			(size 0.3048 0.381)
			(layers "B.Cu" "B.Mask" "B.Paste")
			(net "GND")
		)
	)
	(footprint ""
		(layer "B.Cu")
		(at 424.684444 -426.718222 -90)
		(property "Reference" "R1431"
			(at 0 0 90)
			(layer "B.SilkS")
			(hide yes)
			(effects
				(font
					(size 1.27 1.27)
				)
				(justify mirror)
			)
		)
		(property "Value" ""
			(at 0 0 90)
			(layer "B.Fab")
			(effects
				(font
					(size 1.27 1.27)
				)
				(justify mirror)
			)
		)
		(duplicate_pad_numbers_are_jumpers no)
		(fp_line
			(start -0.32512 0.175006)
			(end 0.32512 0.175006)
			(stroke
				(width 0.1)
				(type default)
			)
			(layer "B.Fab")
		)
		(fp_line
			(start 0.32512 0.175006)
			(end 0.32512 -0.175006)
			(stroke
				(width 0.1)
				(type default)
			)
			(layer "B.Fab")
		)
		(fp_line
			(start -0.32512 -0.175006)
			(end -0.32512 0.175006)
			(stroke
				(width 0.1)
				(type default)
			)
			(layer "B.Fab")
		)
		(fp_line
			(start 0.32512 -0.175006)
			(end -0.32512 -0.175006)
			(stroke
				(width 0.1)
				(type default)
			)
			(layer "B.Fab")
		)
		(pad "1" smd rect
			(at 0.2667 0 90)
			(size 0.3048 0.381)
			(layers "B.Cu" "B.Mask" "B.Paste")
			(net "P1V8_CPU0_RT_1D")
		)
		(pad "2" smd rect
			(at -0.2667 0 270)
			(size 0.3048 0.381)
			(layers "B.Cu" "B.Mask" "B.Paste")
			(net "SMB_RT_CPU0_P2_ROM_MUX_1D_SDA")
		)
	)
	(footprint ""
		(layer "B.Cu")
		(at 43.265852 -383.49936 180)
		(property "Reference" "R6723"
			(at 0 0 0)
			(layer "B.SilkS")
			(hide yes)
			(effects
				(font
					(size 1.27 1.27)
				)
				(justify mirror)
			)
		)
		(property "Value" ""
			(at 0 0 0)
			(layer "B.Fab")
			(effects
				(font
					(size 1.27 1.27)
				)
				(justify mirror)
			)
		)
		(duplicate_pad_numbers_are_jumpers no)
		(fp_line
			(start 0.32512 0.175006)
			(end 0.32512 -0.175006)
			(stroke
				(width 0.1)
				(type default)
			)
			(layer "B.Fab")
		)
		(fp_line
			(start 0.32512 -0.175006)
			(end -0.32512 -0.175006)
			(stroke
				(width 0.1)
				(type default)
			)
			(layer "B.Fab")
		)
		(fp_line
			(start -0.32512 0.175006)
			(end 0.32512 0.175006)
			(stroke
				(width 0.1)
				(type default)
			)
			(layer "B.Fab")
		)
		(fp_line
			(start -0.32512 -0.175006)
			(end -0.32512 0.175006)
			(stroke
				(width 0.1)
				(type default)
			)
			(layer "B.Fab")
		)
		(pad "1" smd rect
			(at 0.2667 0)
			(size 0.3048 0.381)
			(layers "B.Cu" "B.Mask" "B.Paste")
			(net "RT_CPU1_P0_SCAN_MODE")
		)
		(pad "2" smd rect
			(at -0.2667 0 180)
			(size 0.3048 0.381)
			(layers "B.Cu" "B.Mask" "B.Paste")
			(net "GND")
		)
	)
)
